(kicad_pcb
	(version 20260206)
	(generator "pcbnew")
	(generator_version "10.0")
	(general
		(thickness 1.6)
		(legacy_teardrops no)
	)
	(paper "A4")
	(title_block
		(title "04192023_DAF0TMB3IC0_F0TG_MB_C_brd_V02_OCP.brd")
		(comment 1 "Grand Teton / footprints 2111-2116 of 8354")
	)
	(layers
		(0 "F.Cu" signal "TOP")
		(4 "In1.Cu" signal "GND")
		(6 "In2.Cu" signal "IN1")
		(8 "In3.Cu" signal "GND1")
		(10 "In4.Cu" signal "IN2")
		(12 "In5.Cu" signal "GND2")
		(14 "In6.Cu" signal "IN3")
		(16 "In7.Cu" signal "GND3")
		(18 "In8.Cu" signal "VCC")
		(20 "In9.Cu" signal "VCC1")
		(22 "In10.Cu" signal "GND4")
		(24 "In11.Cu" signal "IN4")
		(26 "In12.Cu" signal "GND5")
		(28 "In13.Cu" signal "IN5")
		(30 "In14.Cu" signal "GND6")
		(32 "In15.Cu" signal "IN6")
		(34 "In16.Cu" signal "GND7")
		(2 "B.Cu" signal "BOTTOM")
		(9 "F.Adhes" user "F.Adhesive")
		(11 "B.Adhes" user "B.Adhesive")
		(13 "F.Paste" user "Package Geometry/Pastemask Top")
		(15 "B.Paste" user "Package Geometry/Pastemask Bottom")
		(5 "F.SilkS" user "Ref Des/Silkscreen Top")
		(7 "B.SilkS" user "Ref Des/Silkscreen Bottom")
		(1 "F.Mask" user "Board Geometry/Soldermask Top")
		(3 "B.Mask" user "Board Geometry/Soldermask Bottom")
		(17 "Dwgs.User" user "User.Drawings")
		(19 "Cmts.User" user "User.Comments")
		(21 "Eco1.User" user "User.Eco1")
		(23 "Eco2.User" user "User.Eco2")
		(25 "Edge.Cuts" user "Board Geometry/Outline")
		(27 "Margin" user)
		(31 "F.CrtYd" user "Package Geometry/Place Bound Top")
		(29 "B.CrtYd" user "Package Geometry/Place Bound Bottom")
		(35 "F.Fab" user "Ref Des/Assembly Top")
		(33 "B.Fab" user "Ref Des/Assembly Bottom")
	)
	(footprint ""
		(layer "F.Cu")
		(at 249.896122 -380.66853)
		(property "Reference" "PR2536"
			(at 0 0 0)
			(layer "F.SilkS")
			(hide yes)
			(effects
				(font
					(size 1.27 1.27)
				)
			)
		)
		(property "Value" ""
			(at 0 0 0)
			(layer "F.Fab")
			(effects
				(font
					(size 1.27 1.27)
				)
			)
		)
		(duplicate_pad_numbers_are_jumpers no)
		(fp_line
			(start -0.7874 -0.4064)
			(end 0.7874 -0.4064)
			(stroke
				(width 0.1524)
				(type default)
			)
			(layer "F.SilkS")
		)
		(fp_line
			(start -0.7874 0.4064)
			(end -0.7874 -0.4064)
			(stroke
				(width 0.1524)
				(type default)
			)
			(layer "F.SilkS")
		)
		(fp_line
			(start 0.7874 -0.4064)
			(end 0.7874 0.4064)
			(stroke
				(width 0.1524)
				(type default)
			)
			(layer "F.SilkS")
		)
		(fp_line
			(start 0.7874 0.4064)
			(end -0.7874 0.4064)
			(stroke
				(width 0.1524)
				(type default)
			)
			(layer "F.SilkS")
		)
		(fp_line
			(start -0.67945 -0.305054)
			(end -0.12065 -0.305054)
			(stroke
				(width 0.1)
				(type default)
			)
			(layer "F.Fab")
		)
		(fp_line
			(start -0.67945 0.3048)
			(end -0.67945 -0.305054)
			(stroke
				(width 0.1)
				(type default)
			)
			(layer "F.Fab")
		)
		(fp_line
			(start -0.12065 -0.305054)
			(end -0.12065 -0.2794)
			(stroke
				(width 0.1)
				(type default)
			)
			(layer "F.Fab")
		)
		(fp_line
			(start -0.12065 -0.2794)
			(end 0.12065 -0.2794)
			(stroke
				(width 0.1)
				(type default)
			)
			(layer "F.Fab")
		)
		(fp_line
			(start -0.12065 0.2794)
			(end -0.12065 0.3048)
			(stroke
				(width 0.1)
				(type default)
			)
			(layer "F.Fab")
		)
		(fp_line
			(start -0.12065 0.3048)
			(end -0.67945 0.3048)
			(stroke
				(width 0.1)
				(type default)
			)
			(layer "F.Fab")
		)
		(fp_line
			(start 0.120396 0.2794)
			(end -0.12065 0.2794)
			(stroke
				(width 0.1)
				(type default)
			)
			(layer "F.Fab")
		)
		(fp_line
			(start 0.120396 0.3048)
			(end 0.120396 0.2794)
			(stroke
				(width 0.1)
				(type default)
			)
			(layer "F.Fab")
		)
		(fp_line
			(start 0.12065 -0.3048)
			(end 0.67945 -0.3048)
			(stroke
				(width 0.1)
				(type default)
			)
			(layer "F.Fab")
		)
		(fp_line
			(start 0.12065 -0.2794)
			(end 0.12065 -0.3048)
			(stroke
				(width 0.1)
				(type default)
			)
			(layer "F.Fab")
		)
		(fp_line
			(start 0.67945 -0.3048)
			(end 0.67945 0.3048)
			(stroke
				(width 0.1)
				(type default)
			)
			(layer "F.Fab")
		)
		(fp_line
			(start 0.67945 0.3048)
			(end 0.120396 0.3048)
			(stroke
				(width 0.1)
				(type default)
			)
			(layer "F.Fab")
		)
		(pad "1" smd circle
			(at -0.40005 0)
			(size 0 0)
			(layers "F.Cu" "F.Mask" "F.Paste")
			(net "P12V_HSC_GATE_G6")
		)
		(pad "2" smd circle
			(at 0.40005 0)
			(size 0 0)
			(layers "F.Cu" "F.Mask" "F.Paste")
			(net "P12V_HSC_GATE2")
		)
	)
	(footprint ""
		(layer "F.Cu")
		(at 215.98128 -41.341548)
		(property "Reference" "C1997"
			(at 0 0 0)
			(layer "F.SilkS")
			(hide yes)
			(effects
				(font
					(size 1.27 1.27)
				)
			)
		)
		(property "Value" ""
			(at 0 0 0)
			(layer "F.Fab")
			(effects
				(font
					(size 1.27 1.27)
				)
			)
		)
		(duplicate_pad_numbers_are_jumpers no)
		(fp_line
			(start -0.7874 -0.4064)
			(end 0.7874 -0.4064)
			(stroke
				(width 0.1524)
				(type default)
			)
			(layer "F.SilkS")
		)
		(fp_line
			(start -0.7874 0.4064)
			(end -0.7874 -0.4064)
			(stroke
				(width 0.1524)
				(type default)
			)
			(layer "F.SilkS")
		)
		(fp_line
			(start 0.7874 -0.4064)
			(end 0.7874 0.4064)
			(stroke
				(width 0.1524)
				(type default)
			)
			(layer "F.SilkS")
		)
		(fp_line
			(start 0.7874 0.4064)
			(end -0.7874 0.4064)
			(stroke
				(width 0.1524)
				(type default)
			)
			(layer "F.SilkS")
		)
		(fp_line
			(start -0.67945 -0.305054)
			(end -0.12065 -0.305054)
			(stroke
				(width 0.1)
				(type default)
			)
			(layer "F.Fab")
		)
		(fp_line
			(start -0.67945 0.3048)
			(end -0.67945 -0.305054)
			(stroke
				(width 0.1)
				(type default)
			)
			(layer "F.Fab")
		)
		(fp_line
			(start -0.12065 -0.305054)
			(end -0.12065 -0.2794)
			(stroke
				(width 0.1)
				(type default)
			)
			(layer "F.Fab")
		)
		(fp_line
			(start -0.12065 -0.2794)
			(end 0.12065 -0.2794)
			(stroke
				(width 0.1)
				(type default)
			)
			(layer "F.Fab")
		)
		(fp_line
			(start -0.12065 0.2794)
			(end -0.12065 0.3048)
			(stroke
				(width 0.1)
				(type default)
			)
			(layer "F.Fab")
		)
		(fp_line
			(start -0.12065 0.3048)
			(end -0.67945 0.3048)
			(stroke
				(width 0.1)
				(type default)
			)
			(layer "F.Fab")
		)
		(fp_line
			(start 0.120396 0.2794)
			(end -0.12065 0.2794)
			(stroke
				(width 0.1)
				(type default)
			)
			(layer "F.Fab")
		)
		(fp_line
			(start 0.120396 0.3048)
			(end 0.120396 0.2794)
			(stroke
				(width 0.1)
				(type default)
			)
			(layer "F.Fab")
		)
		(fp_line
			(start 0.12065 -0.3048)
			(end 0.67945 -0.3048)
			(stroke
				(width 0.1)
				(type default)
			)
			(layer "F.Fab")
		)
		(fp_line
			(start 0.12065 -0.2794)
			(end 0.12065 -0.3048)
			(stroke
				(width 0.1)
				(type default)
			)
			(layer "F.Fab")
		)
		(fp_line
			(start 0.67945 -0.3048)
			(end 0.67945 0.3048)
			(stroke
				(width 0.1)
				(type default)
			)
			(layer "F.Fab")
		)
		(fp_line
			(start 0.67945 0.3048)
			(end 0.120396 0.3048)
			(stroke
				(width 0.1)
				(type default)
			)
			(layer "F.Fab")
		)
		(pad "1" smd circle
			(at -0.40005 0)
			(size 0 0)
			(layers "F.Cu" "F.Mask" "F.Paste")
			(net "P3V3_AUX")
		)
		(pad "2" smd circle
			(at 0.40005 0)
			(size 0 0)
			(layers "F.Cu" "F.Mask" "F.Paste")
			(net "GND")
		)
	)
	(footprint ""
		(layer "F.Cu")
		(at 42.672 -171.831)
		(property "Reference" "R565"
			(at 0 0 0)
			(layer "F.SilkS")
			(hide yes)
			(effects
				(font
					(size 1.27 1.27)
				)
			)
		)
		(property "Value" ""
			(at 0 0 0)
			(layer "F.Fab")
			(effects
				(font
					(size 1.27 1.27)
				)
			)
		)
		(duplicate_pad_numbers_are_jumpers no)
		(fp_line
			(start -0.7874 -0.4064)
			(end 0.7874 -0.4064)
			(stroke
				(width 0.1524)
				(type default)
			)
			(layer "F.SilkS")
		)
		(fp_line
			(start -0.7874 0.4064)
			(end -0.7874 -0.4064)
			(stroke
				(width 0.1524)
				(type default)
			)
			(layer "F.SilkS")
		)
		(fp_line
			(start 0.7874 -0.4064)
			(end 0.7874 0.4064)
			(stroke
				(width 0.1524)
				(type default)
			)
			(layer "F.SilkS")
		)
		(fp_line
			(start 0.7874 0.4064)
			(end -0.7874 0.4064)
			(stroke
				(width 0.1524)
				(type default)
			)
			(layer "F.SilkS")
		)
		(fp_line
			(start -0.67945 -0.305054)
			(end -0.12065 -0.305054)
			(stroke
				(width 0.1)
				(type default)
			)
			(layer "F.Fab")
		)
		(fp_line
			(start -0.67945 0.3048)
			(end -0.67945 -0.305054)
			(stroke
				(width 0.1)
				(type default)
			)
			(layer "F.Fab")
		)
		(fp_line
			(start -0.12065 -0.305054)
			(end -0.12065 -0.2794)
			(stroke
				(width 0.1)
				(type default)
			)
			(layer "F.Fab")
		)
		(fp_line
			(start -0.12065 -0.2794)
			(end 0.12065 -0.2794)
			(stroke
				(width 0.1)
				(type default)
			)
			(layer "F.Fab")
		)
		(fp_line
			(start -0.12065 0.2794)
			(end -0.12065 0.3048)
			(stroke
				(width 0.1)
				(type default)
			)
			(layer "F.Fab")
		)
		(fp_line
			(start -0.12065 0.3048)
			(end -0.67945 0.3048)
			(stroke
				(width 0.1)
				(type default)
			)
			(layer "F.Fab")
		)
		(fp_line
			(start 0.120396 0.2794)
			(end -0.12065 0.2794)
			(stroke
				(width 0.1)
				(type default)
			)
			(layer "F.Fab")
		)
		(fp_line
			(start 0.120396 0.3048)
			(end 0.120396 0.2794)
			(stroke
				(width 0.1)
				(type default)
			)
			(layer "F.Fab")
		)
		(fp_line
			(start 0.12065 -0.3048)
			(end 0.67945 -0.3048)
			(stroke
				(width 0.1)
				(type default)
			)
			(layer "F.Fab")
		)
		(fp_line
			(start 0.12065 -0.2794)
			(end 0.12065 -0.3048)
			(stroke
				(width 0.1)
				(type default)
			)
			(layer "F.Fab")
		)
		(fp_line
			(start 0.67945 -0.3048)
			(end 0.67945 0.3048)
			(stroke
				(width 0.1)
				(type default)
			)
			(layer "F.Fab")
		)
		(fp_line
			(start 0.67945 0.3048)
			(end 0.120396 0.3048)
			(stroke
				(width 0.1)
				(type default)
			)
			(layer "F.Fab")
		)
		(pad "1" smd rect
			(at -0.40005 0 180)
			(size 0.4572 0.508)
			(layers "F.Cu" "F.Mask" "F.Paste")
			(net "I3C_0_SPD_DDRAF_CPU1_SDA")
		)
		(pad "2" smd rect
			(at 0.40005 0 180)
			(size 0.4572 0.508)
			(layers "F.Cu" "F.Mask" "F.Paste")
			(net "I3C_0_SPD_DDRAF_CPU1_R_SDA")
		)
	)
	(footprint ""
		(layer "F.Cu")
		(at 114.325908 -256.012442 90)
		(property "Reference" "C3906"
			(at 0 0 90)
			(layer "F.SilkS")
			(hide yes)
			(effects
				(font
					(size 1.27 1.27)
				)
			)
		)
		(property "Value" ""
			(at 0 0 90)
			(layer "F.Fab")
			(effects
				(font
					(size 1.27 1.27)
				)
			)
		)
		(duplicate_pad_numbers_are_jumpers no)
		(fp_line
			(start 0.7874 -0.4064)
			(end 0.7874 0.4064)
			(stroke
				(width 0.1524)
				(type default)
			)
			(layer "F.SilkS")
		)
		(fp_line
			(start -0.7874 -0.4064)
			(end 0.7874 -0.4064)
			(stroke
				(width 0.1524)
				(type default)
			)
			(layer "F.SilkS")
		)
		(fp_line
			(start 0.7874 0.4064)
			(end -0.7874 0.4064)
			(stroke
				(width 0.1524)
				(type default)
			)
			(layer "F.SilkS")
		)
		(fp_line
			(start -0.7874 0.4064)
			(end -0.7874 -0.4064)
			(stroke
				(width 0.1524)
				(type default)
			)
			(layer "F.SilkS")
		)
		(fp_line
			(start -0.12065 -0.305054)
			(end -0.12065 -0.2794)
			(stroke
				(width 0.1)
				(type default)
			)
			(layer "F.Fab")
		)
		(fp_line
			(start -0.67945 -0.305054)
			(end -0.12065 -0.305054)
			(stroke
				(width 0.1)
				(type default)
			)
			(layer "F.Fab")
		)
		(fp_line
			(start 0.67945 -0.3048)
			(end 0.67945 0.3048)
			(stroke
				(width 0.1)
				(type default)
			)
			(layer "F.Fab")
		)
		(fp_line
			(start 0.12065 -0.3048)
			(end 0.67945 -0.3048)
			(stroke
				(width 0.1)
				(type default)
			)
			(layer "F.Fab")
		)
		(fp_line
			(start 0.12065 -0.2794)
			(end 0.12065 -0.3048)
			(stroke
				(width 0.1)
				(type default)
			)
			(layer "F.Fab")
		)
		(fp_line
			(start -0.12065 -0.2794)
			(end 0.12065 -0.2794)
			(stroke
				(width 0.1)
				(type default)
			)
			(layer "F.Fab")
		)
		(fp_line
			(start 0.120396 0.2794)
			(end -0.12065 0.2794)
			(stroke
				(width 0.1)
				(type default)
			)
			(layer "F.Fab")
		)
		(fp_line
			(start -0.12065 0.2794)
			(end -0.12065 0.3048)
			(stroke
				(width 0.1)
				(type default)
			)
			(layer "F.Fab")
		)
		(fp_line
			(start 0.67945 0.3048)
			(end 0.120396 0.3048)
			(stroke
				(width 0.1)
				(type default)
			)
			(layer "F.Fab")
		)
		(fp_line
			(start 0.120396 0.3048)
			(end 0.120396 0.2794)
			(stroke
				(width 0.1)
				(type default)
			)
			(layer "F.Fab")
		)
		(fp_line
			(start -0.12065 0.3048)
			(end -0.67945 0.3048)
			(stroke
				(width 0.1)
				(type default)
			)
			(layer "F.Fab")
		)
		(fp_line
			(start -0.67945 0.3048)
			(end -0.67945 -0.305054)
			(stroke
				(width 0.1)
				(type default)
			)
			(layer "F.Fab")
		)
		(pad "1" smd circle
			(at -0.40005 0 90)
			(size 0 0)
			(layers "F.Cu" "F.Mask" "F.Paste")
			(net "PVDDCR_SOC_P1")
		)
		(pad "2" smd circle
			(at 0.40005 0 90)
			(size 0 0)
			(layers "F.Cu" "F.Mask" "F.Paste")
			(net "GND")
		)
	)
	(footprint ""
		(layer "F.Cu")
		(at 401.507198 -177.172874 90)
		(property "Reference" "PC581_SOP0_1"
			(at 0 0 90)
			(layer "F.SilkS")
			(hide yes)
			(effects
				(font
					(size 1.27 1.27)
				)
			)
		)
		(property "Value" ""
			(at 0 0 90)
			(layer "F.Fab")
			(effects
				(font
					(size 1.27 1.27)
				)
			)
		)
		(duplicate_pad_numbers_are_jumpers no)
		(fp_line
			(start 0.7874 -0.4064)
			(end 0.7874 0.4064)
			(stroke
				(width 0.1524)
				(type default)
			)
			(layer "F.SilkS")
		)
		(fp_line
			(start -0.7874 -0.4064)
			(end 0.7874 -0.4064)
			(stroke
				(width 0.1524)
				(type default)
			)
			(layer "F.SilkS")
		)
		(fp_line
			(start 0.7874 0.4064)
			(end -0.7874 0.4064)
			(stroke
				(width 0.1524)
				(type default)
			)
			(layer "F.SilkS")
		)
		(fp_line
			(start -0.7874 0.4064)
			(end -0.7874 -0.4064)
			(stroke
				(width 0.1524)
				(type default)
			)
			(layer "F.SilkS")
		)
		(fp_line
			(start -0.12065 -0.305054)
			(end -0.12065 -0.2794)
			(stroke
				(width 0.1)
				(type default)
			)
			(layer "F.Fab")
		)
		(fp_line
			(start -0.67945 -0.305054)
			(end -0.12065 -0.305054)
			(stroke
				(width 0.1)
				(type default)
			)
			(layer "F.Fab")
		)
		(fp_line
			(start 0.67945 -0.3048)
			(end 0.67945 0.3048)
			(stroke
				(width 0.1)
				(type default)
			)
			(layer "F.Fab")
		)
		(fp_line
			(start 0.12065 -0.3048)
			(end 0.67945 -0.3048)
			(stroke
				(width 0.1)
				(type default)
			)
			(layer "F.Fab")
		)
		(fp_line
			(start 0.12065 -0.2794)
			(end 0.12065 -0.3048)
			(stroke
				(width 0.1)
				(type default)
			)
			(layer "F.Fab")
		)
		(fp_line
			(start -0.12065 -0.2794)
			(end 0.12065 -0.2794)
			(stroke
				(width 0.1)
				(type default)
			)
			(layer "F.Fab")
		)
		(fp_line
			(start 0.120396 0.2794)
			(end -0.12065 0.2794)
			(stroke
				(width 0.1)
				(type default)
			)
			(layer "F.Fab")
		)
		(fp_line
			(start -0.12065 0.2794)
			(end -0.12065 0.3048)
			(stroke
				(width 0.1)
				(type default)
			)
			(layer "F.Fab")
		)
		(fp_line
			(start 0.67945 0.3048)
			(end 0.120396 0.3048)
			(stroke
				(width 0.1)
				(type default)
			)
			(layer "F.Fab")
		)
		(fp_line
			(start 0.120396 0.3048)
			(end 0.120396 0.2794)
			(stroke
				(width 0.1)
				(type default)
			)
			(layer "F.Fab")
		)
		(fp_line
			(start -0.12065 0.3048)
			(end -0.67945 0.3048)
			(stroke
				(width 0.1)
				(type default)
			)
			(layer "F.Fab")
		)
		(fp_line
			(start -0.67945 0.3048)
			(end -0.67945 -0.305054)
			(stroke
				(width 0.1)
				(type default)
			)
			(layer "F.Fab")
		)
		(pad "1" smd circle
			(at -0.40005 0 90)
			(size 0 0)
			(layers "F.Cu" "F.Mask" "F.Paste")
			(net "PVDDCR_CPU0_P0_PVCC")
		)
		(pad "2" smd circle
			(at 0.40005 0 90)
			(size 0 0)
			(layers "F.Cu" "F.Mask" "F.Paste")
			(net "GND")
		)
	)
	(footprint ""
		(layer "F.Cu")
		(at 30.484064 -80.424274 90)
		(property "Reference" "R1313"
			(at 0 0 90)
			(layer "F.SilkS")
			(hide yes)
			(effects
				(font
					(size 1.27 1.27)
				)
			)
		)
		(property "Value" ""
			(at 0 0 90)
			(layer "F.Fab")
			(effects
				(font
					(size 1.27 1.27)
				)
			)
		)
		(duplicate_pad_numbers_are_jumpers no)
		(fp_line
			(start 0.7874 -0.4064)
			(end 0.7874 0.4064)
			(stroke
				(width 0.1524)
				(type default)
			)
			(layer "F.SilkS")
		)
		(fp_line
			(start -0.7874 -0.4064)
			(end 0.7874 -0.4064)
			(stroke
				(width 0.1524)
				(type default)
			)
			(layer "F.SilkS")
		)
		(fp_line
			(start 0.7874 0.4064)
			(end -0.7874 0.4064)
			(stroke
				(width 0.1524)
				(type default)
			)
			(layer "F.SilkS")
		)
		(fp_line
			(start -0.7874 0.4064)
			(end -0.7874 -0.4064)
			(stroke
				(width 0.1524)
				(type default)
			)
			(layer "F.SilkS")
		)
		(fp_line
			(start -0.12065 -0.305054)
			(end -0.12065 -0.2794)
			(stroke
				(width 0.1)
				(type default)
			)
			(layer "F.Fab")
		)
		(fp_line
			(start -0.67945 -0.305054)
			(end -0.12065 -0.305054)
			(stroke
				(width 0.1)
				(type default)
			)
			(layer "F.Fab")
		)
		(fp_line
			(start 0.67945 -0.3048)
			(end 0.67945 0.3048)
			(stroke
				(width 0.1)
				(type default)
			)
			(layer "F.Fab")
		)
		(fp_line
			(start 0.12065 -0.3048)
			(end 0.67945 -0.3048)
			(stroke
				(width 0.1)
				(type default)
			)
			(layer "F.Fab")
		)
		(fp_line
			(start 0.12065 -0.2794)
			(end 0.12065 -0.3048)
			(stroke
				(width 0.1)
				(type default)
			)
			(layer "F.Fab")
		)
		(fp_line
			(start -0.12065 -0.2794)
			(end 0.12065 -0.2794)
			(stroke
				(width 0.1)
				(type default)
			)
			(layer "F.Fab")
		)
		(fp_line
			(start 0.120396 0.2794)
			(end -0.12065 0.2794)
			(stroke
				(width 0.1)
				(type default)
			)
			(layer "F.Fab")
		)
		(fp_line
			(start -0.12065 0.2794)
			(end -0.12065 0.3048)
			(stroke
				(width 0.1)
				(type default)
			)
			(layer "F.Fab")
		)
		(fp_line
			(start 0.67945 0.3048)
			(end 0.120396 0.3048)
			(stroke
				(width 0.1)
				(type default)
			)
			(layer "F.Fab")
		)
		(fp_line
			(start 0.120396 0.3048)
			(end 0.120396 0.2794)
			(stroke
				(width 0.1)
				(type default)
			)
			(layer "F.Fab")
		)
		(fp_line
			(start -0.12065 0.3048)
			(end -0.67945 0.3048)
			(stroke
				(width 0.1)
				(type default)
			)
			(layer "F.Fab")
		)
		(fp_line
			(start -0.67945 0.3048)
			(end -0.67945 -0.305054)
			(stroke
				(width 0.1)
				(type default)
			)
			(layer "F.Fab")
		)
		(pad "1" smd circle
			(at -0.40005 0 90)
			(size 0 0)
			(layers "F.Cu" "F.Mask" "F.Paste")
			(net "PD_U160_EN_N")
		)
		(pad "2" smd circle
			(at 0.40005 0 90)
			(size 0 0)
			(layers "F.Cu" "F.Mask" "F.Paste")
			(net "GND")
		)
	)
)
